(kicad_pcb
	(version 20260206)
	(generator "pcbnew")
	(generator_version "10.0")
	(general
		(thickness 1.6)
		(legacy_teardrops no)
	)
	(paper "A4")
	(title_block
		(title "04192023_DAF0TMB3IC0_F0TG_MB_C_brd_V02_OCP.brd")
		(comment 1 "Grand Teton / footprints 2594-2600 of 8354")
	)
	(layers
		(0 "F.Cu" signal "TOP")
		(4 "In1.Cu" signal "GND")
		(6 "In2.Cu" signal "IN1")
		(8 "In3.Cu" signal "GND1")
		(10 "In4.Cu" signal "IN2")
		(12 "In5.Cu" signal "GND2")
		(14 "In6.Cu" signal "IN3")
		(16 "In7.Cu" signal "GND3")
		(18 "In8.Cu" signal "VCC")
		(20 "In9.Cu" signal "VCC1")
		(22 "In10.Cu" signal "GND4")
		(24 "In11.Cu" signal "IN4")
		(26 "In12.Cu" signal "GND5")
		(28 "In13.Cu" signal "IN5")
		(30 "In14.Cu" signal "GND6")
		(32 "In15.Cu" signal "IN6")
		(34 "In16.Cu" signal "GND7")
		(2 "B.Cu" signal "BOTTOM")
		(9 "F.Adhes" user "F.Adhesive")
		(11 "B.Adhes" user "B.Adhesive")
		(13 "F.Paste" user "Package Geometry/Pastemask Top")
		(15 "B.Paste" user "Package Geometry/Pastemask Bottom")
		(5 "F.SilkS" user "Ref Des/Silkscreen Top")
		(7 "B.SilkS" user "Ref Des/Silkscreen Bottom")
		(1 "F.Mask" user "Board Geometry/Soldermask Top")
		(3 "B.Mask" user "Board Geometry/Soldermask Bottom")
		(17 "Dwgs.User" user "User.Drawings")
		(19 "Cmts.User" user "User.Comments")
		(21 "Eco1.User" user "User.Eco1")
		(23 "Eco2.User" user "User.Eco2")
		(25 "Edge.Cuts" user "Board Geometry/Outline")
		(27 "Margin" user)
		(31 "F.CrtYd" user "Package Geometry/Place Bound Top")
		(29 "B.CrtYd" user "Package Geometry/Place Bound Bottom")
		(35 "F.Fab" user "Ref Des/Assembly Top")
		(33 "B.Fab" user "Ref Des/Assembly Bottom")
	)
	(footprint ""
		(layer "F.Cu")
		(at 43.4721 -170.307)
		(property "Reference" "R988"
			(at 0 0 0)
			(layer "F.SilkS")
			(hide yes)
			(effects
				(font
					(size 1.27 1.27)
				)
			)
		)
		(property "Value" ""
			(at 0 0 0)
			(layer "F.Fab")
			(effects
				(font
					(size 1.27 1.27)
				)
			)
		)
		(duplicate_pad_numbers_are_jumpers no)
		(fp_line
			(start -0.7874 -0.4064)
			(end 0.7874 -0.4064)
			(stroke
				(width 0.1524)
				(type default)
			)
			(layer "F.SilkS")
		)
		(fp_line
			(start -0.7874 0.4064)
			(end -0.7874 -0.4064)
			(stroke
				(width 0.1524)
				(type default)
			)
			(layer "F.SilkS")
		)
		(fp_line
			(start 0.7874 -0.4064)
			(end 0.7874 0.4064)
			(stroke
				(width 0.1524)
				(type default)
			)
			(layer "F.SilkS")
		)
		(fp_line
			(start 0.7874 0.4064)
			(end -0.7874 0.4064)
			(stroke
				(width 0.1524)
				(type default)
			)
			(layer "F.SilkS")
		)
		(fp_line
			(start -0.67945 -0.305054)
			(end -0.12065 -0.305054)
			(stroke
				(width 0.1)
				(type default)
			)
			(layer "F.Fab")
		)
		(fp_line
			(start -0.67945 0.3048)
			(end -0.67945 -0.305054)
			(stroke
				(width 0.1)
				(type default)
			)
			(layer "F.Fab")
		)
		(fp_line
			(start -0.12065 -0.305054)
			(end -0.12065 -0.2794)
			(stroke
				(width 0.1)
				(type default)
			)
			(layer "F.Fab")
		)
		(fp_line
			(start -0.12065 -0.2794)
			(end 0.12065 -0.2794)
			(stroke
				(width 0.1)
				(type default)
			)
			(layer "F.Fab")
		)
		(fp_line
			(start -0.12065 0.2794)
			(end -0.12065 0.3048)
			(stroke
				(width 0.1)
				(type default)
			)
			(layer "F.Fab")
		)
		(fp_line
			(start -0.12065 0.3048)
			(end -0.67945 0.3048)
			(stroke
				(width 0.1)
				(type default)
			)
			(layer "F.Fab")
		)
		(fp_line
			(start 0.120396 0.2794)
			(end -0.12065 0.2794)
			(stroke
				(width 0.1)
				(type default)
			)
			(layer "F.Fab")
		)
		(fp_line
			(start 0.120396 0.3048)
			(end 0.120396 0.2794)
			(stroke
				(width 0.1)
				(type default)
			)
			(layer "F.Fab")
		)
		(fp_line
			(start 0.12065 -0.3048)
			(end 0.67945 -0.3048)
			(stroke
				(width 0.1)
				(type default)
			)
			(layer "F.Fab")
		)
		(fp_line
			(start 0.12065 -0.2794)
			(end 0.12065 -0.3048)
			(stroke
				(width 0.1)
				(type default)
			)
			(layer "F.Fab")
		)
		(fp_line
			(start 0.67945 -0.3048)
			(end 0.67945 0.3048)
			(stroke
				(width 0.1)
				(type default)
			)
			(layer "F.Fab")
		)
		(fp_line
			(start 0.67945 0.3048)
			(end 0.120396 0.3048)
			(stroke
				(width 0.1)
				(type default)
			)
			(layer "F.Fab")
		)
		(pad "1" smd rect
			(at -0.40005 0 180)
			(size 0.4572 0.508)
			(layers "F.Cu" "F.Mask" "F.Paste")
			(net "I3C_0_SPD_DDRAF_CPU1_R_SCL")
		)
		(pad "2" smd rect
			(at 0.40005 0 180)
			(size 0.4572 0.508)
			(layers "F.Cu" "F.Mask" "F.Paste")
			(net "I3C_SPD_DDRAF_CPU1_BYPASS_SCL")
		)
	)
	(footprint ""
		(layer "F.Cu")
		(at 304.305716 -437.820308 180)
		(property "Reference" "Q129"
			(at 1.52908 -1.79832 0)
			(unlocked yes)
			(layer "F.SilkS")
			(effects
				(font
					(size 0.7874 0.5842)
					(thickness 0.1524)
				)
				(justify left)
			)
		)
		(property "Value" ""
			(at 0 0 180)
			(layer "F.Fab")
			(effects
				(font
					(size 1.27 1.27)
				)
			)
		)
		(duplicate_pad_numbers_are_jumpers no)
		(fp_line
			(start 1.332738 1.100074)
			(end -1.332738 1.100074)
			(stroke
				(width 0.1524)
				(type default)
			)
			(layer "F.SilkS")
		)
		(fp_line
			(start 1.332738 -1.100074)
			(end 1.332738 1.100074)
			(stroke
				(width 0.1524)
				(type default)
			)
			(layer "F.SilkS")
		)
		(fp_line
			(start 0.4826 -1.100074)
			(end 1.332738 -1.100074)
			(stroke
				(width 0.1524)
				(type default)
			)
			(layer "F.SilkS")
		)
		(fp_line
			(start 0 -0.541274)
			(end 0.4826 -1.100074)
			(stroke
				(width 0.1524)
				(type default)
			)
			(layer "F.SilkS")
		)
		(fp_line
			(start -0.4826 -1.100074)
			(end 0 -0.541274)
			(stroke
				(width 0.1524)
				(type default)
			)
			(layer "F.SilkS")
		)
		(fp_line
			(start -1.332738 1.100074)
			(end -1.332738 -1.100074)
			(stroke
				(width 0.1524)
				(type default)
			)
			(layer "F.SilkS")
		)
		(fp_line
			(start -1.332738 -1.100074)
			(end -0.4826 -1.100074)
			(stroke
				(width 0.1524)
				(type default)
			)
			(layer "F.SilkS")
		)
		(fp_poly
			(pts
				(xy -1.489456 -1.189482) (xy -2.23393 -1.43764) (xy -1.737614 -1.933956)
			)
			(stroke
				(width 0)
				(type default)
			)
			(fill yes)
			(layer "F.SilkS")
		)
		(fp_line
			(start 0.674878 1.100074)
			(end -0.674878 1.100074)
			(stroke
				(width 0.1)
				(type default)
			)
			(layer "F.Fab")
		)
		(fp_line
			(start 0.674878 -1.100074)
			(end 0.674878 1.100074)
			(stroke
				(width 0.1)
				(type default)
			)
			(layer "F.Fab")
		)
		(fp_line
			(start -0.674878 1.100074)
			(end -0.674878 -1.100074)
			(stroke
				(width 0.1)
				(type default)
			)
			(layer "F.Fab")
		)
		(fp_line
			(start -0.674878 -1.100074)
			(end 0.674878 -1.100074)
			(stroke
				(width 0.1)
				(type default)
			)
			(layer "F.Fab")
		)
		(fp_poly
			(pts
				(xy -2.2352 -0.298958) (xy -2.2352 -1.001014) (xy -1.533144 -0.649986)
			)
			(stroke
				(width 0)
				(type default)
			)
			(fill yes)
			(layer "F.Fab")
		)
		(pad "1" smd rect
			(at -0.94996 -0.649986 270)
			(size 0.4318 0.508)
			(layers "F.Cu" "F.Mask" "F.Paste")
			(net "GND")
		)
		(pad "2" smd rect
			(at -0.94996 0 270)
			(size 0.4318 0.508)
			(layers "F.Cu" "F.Mask" "F.Paste")
			(net "GPU_3V3IO_RSVD5_FFU")
		)
		(pad "3" smd rect
			(at -0.94996 0.649986 270)
			(size 0.4318 0.508)
			(layers "F.Cu" "F.Mask" "F.Paste")
			(net "GPU_3V3IO_RSVD5_FFU_ISO")
		)
		(pad "4" smd rect
			(at 0.94996 0.649986 270)
			(size 0.4318 0.508)
			(layers "F.Cu" "F.Mask" "F.Paste")
			(net "GND")
		)
		(pad "5" smd rect
			(at 0.94996 0 270)
			(size 0.4318 0.508)
			(layers "F.Cu" "F.Mask" "F.Paste")
			(net "GPU_3V3IO_RSVD5_FFU_N")
		)
		(pad "6" smd rect
			(at 0.94996 -0.649986 270)
			(size 0.4318 0.508)
			(layers "F.Cu" "F.Mask" "F.Paste")
			(net "GPU_3V3IO_RSVD5_FFU_N")
		)
	)
	(footprint ""
		(layer "F.Cu")
		(at 364.165896 -256.012188 90)
		(property "Reference" "C2528"
			(at 0 0 90)
			(layer "F.SilkS")
			(hide yes)
			(effects
				(font
					(size 1.27 1.27)
				)
			)
		)
		(property "Value" ""
			(at 0 0 90)
			(layer "F.Fab")
			(effects
				(font
					(size 1.27 1.27)
				)
			)
		)
		(duplicate_pad_numbers_are_jumpers no)
		(fp_line
			(start 0.7874 -0.4064)
			(end 0.7874 0.4064)
			(stroke
				(width 0.1524)
				(type default)
			)
			(layer "F.SilkS")
		)
		(fp_line
			(start -0.7874 -0.4064)
			(end 0.7874 -0.4064)
			(stroke
				(width 0.1524)
				(type default)
			)
			(layer "F.SilkS")
		)
		(fp_line
			(start 0.7874 0.4064)
			(end -0.7874 0.4064)
			(stroke
				(width 0.1524)
				(type default)
			)
			(layer "F.SilkS")
		)
		(fp_line
			(start -0.7874 0.4064)
			(end -0.7874 -0.4064)
			(stroke
				(width 0.1524)
				(type default)
			)
			(layer "F.SilkS")
		)
		(fp_line
			(start -0.12065 -0.305054)
			(end -0.12065 -0.2794)
			(stroke
				(width 0.1)
				(type default)
			)
			(layer "F.Fab")
		)
		(fp_line
			(start -0.67945 -0.305054)
			(end -0.12065 -0.305054)
			(stroke
				(width 0.1)
				(type default)
			)
			(layer "F.Fab")
		)
		(fp_line
			(start 0.67945 -0.3048)
			(end 0.67945 0.3048)
			(stroke
				(width 0.1)
				(type default)
			)
			(layer "F.Fab")
		)
		(fp_line
			(start 0.12065 -0.3048)
			(end 0.67945 -0.3048)
			(stroke
				(width 0.1)
				(type default)
			)
			(layer "F.Fab")
		)
		(fp_line
			(start 0.12065 -0.2794)
			(end 0.12065 -0.3048)
			(stroke
				(width 0.1)
				(type default)
			)
			(layer "F.Fab")
		)
		(fp_line
			(start -0.12065 -0.2794)
			(end 0.12065 -0.2794)
			(stroke
				(width 0.1)
				(type default)
			)
			(layer "F.Fab")
		)
		(fp_line
			(start 0.120396 0.2794)
			(end -0.12065 0.2794)
			(stroke
				(width 0.1)
				(type default)
			)
			(layer "F.Fab")
		)
		(fp_line
			(start -0.12065 0.2794)
			(end -0.12065 0.3048)
			(stroke
				(width 0.1)
				(type default)
			)
			(layer "F.Fab")
		)
		(fp_line
			(start 0.67945 0.3048)
			(end 0.120396 0.3048)
			(stroke
				(width 0.1)
				(type default)
			)
			(layer "F.Fab")
		)
		(fp_line
			(start 0.120396 0.3048)
			(end 0.120396 0.2794)
			(stroke
				(width 0.1)
				(type default)
			)
			(layer "F.Fab")
		)
		(fp_line
			(start -0.12065 0.3048)
			(end -0.67945 0.3048)
			(stroke
				(width 0.1)
				(type default)
			)
			(layer "F.Fab")
		)
		(fp_line
			(start -0.67945 0.3048)
			(end -0.67945 -0.305054)
			(stroke
				(width 0.1)
				(type default)
			)
			(layer "F.Fab")
		)
		(pad "1" smd circle
			(at -0.40005 0 90)
			(size 0 0)
			(layers "F.Cu" "F.Mask" "F.Paste")
			(net "PVDDCR_SOC_P0")
		)
		(pad "2" smd circle
			(at 0.40005 0 90)
			(size 0 0)
			(layers "F.Cu" "F.Mask" "F.Paste")
			(net "GND")
		)
	)
	(footprint ""
		(layer "F.Cu")
		(at 301.621952 -22.12975)
		(property "Reference" "C1563"
			(at 0 0 0)
			(layer "F.SilkS")
			(hide yes)
			(effects
				(font
					(size 1.27 1.27)
				)
			)
		)
		(property "Value" ""
			(at 0 0 0)
			(layer "F.Fab")
			(effects
				(font
					(size 1.27 1.27)
				)
			)
		)
		(duplicate_pad_numbers_are_jumpers no)
		(fp_line
			(start -0.7874 -0.4064)
			(end 0.7874 -0.4064)
			(stroke
				(width 0.1524)
				(type default)
			)
			(layer "F.SilkS")
		)
		(fp_line
			(start -0.7874 0.4064)
			(end -0.7874 -0.4064)
			(stroke
				(width 0.1524)
				(type default)
			)
			(layer "F.SilkS")
		)
		(fp_line
			(start 0.7874 -0.4064)
			(end 0.7874 0.4064)
			(stroke
				(width 0.1524)
				(type default)
			)
			(layer "F.SilkS")
		)
		(fp_line
			(start 0.7874 0.4064)
			(end -0.7874 0.4064)
			(stroke
				(width 0.1524)
				(type default)
			)
			(layer "F.SilkS")
		)
		(fp_line
			(start -0.67945 -0.305054)
			(end -0.12065 -0.305054)
			(stroke
				(width 0.1)
				(type default)
			)
			(layer "F.Fab")
		)
		(fp_line
			(start -0.67945 0.3048)
			(end -0.67945 -0.305054)
			(stroke
				(width 0.1)
				(type default)
			)
			(layer "F.Fab")
		)
		(fp_line
			(start -0.12065 -0.305054)
			(end -0.12065 -0.2794)
			(stroke
				(width 0.1)
				(type default)
			)
			(layer "F.Fab")
		)
		(fp_line
			(start -0.12065 -0.2794)
			(end 0.12065 -0.2794)
			(stroke
				(width 0.1)
				(type default)
			)
			(layer "F.Fab")
		)
		(fp_line
			(start -0.12065 0.2794)
			(end -0.12065 0.3048)
			(stroke
				(width 0.1)
				(type default)
			)
			(layer "F.Fab")
		)
		(fp_line
			(start -0.12065 0.3048)
			(end -0.67945 0.3048)
			(stroke
				(width 0.1)
				(type default)
			)
			(layer "F.Fab")
		)
		(fp_line
			(start 0.120396 0.2794)
			(end -0.12065 0.2794)
			(stroke
				(width 0.1)
				(type default)
			)
			(layer "F.Fab")
		)
		(fp_line
			(start 0.120396 0.3048)
			(end 0.120396 0.2794)
			(stroke
				(width 0.1)
				(type default)
			)
			(layer "F.Fab")
		)
		(fp_line
			(start 0.12065 -0.3048)
			(end 0.67945 -0.3048)
			(stroke
				(width 0.1)
				(type default)
			)
			(layer "F.Fab")
		)
		(fp_line
			(start 0.12065 -0.2794)
			(end 0.12065 -0.3048)
			(stroke
				(width 0.1)
				(type default)
			)
			(layer "F.Fab")
		)
		(fp_line
			(start 0.67945 -0.3048)
			(end 0.67945 0.3048)
			(stroke
				(width 0.1)
				(type default)
			)
			(layer "F.Fab")
		)
		(fp_line
			(start 0.67945 0.3048)
			(end 0.120396 0.3048)
			(stroke
				(width 0.1)
				(type default)
			)
			(layer "F.Fab")
		)
		(pad "1" smd circle
			(at -0.40005 0)
			(size 0 0)
			(layers "F.Cu" "F.Mask" "F.Paste")
			(net "CLR_CMOS")
		)
		(pad "2" smd circle
			(at 0.40005 0)
			(size 0 0)
			(layers "F.Cu" "F.Mask" "F.Paste")
			(net "GND")
		)
	)
	(footprint ""
		(layer "F.Cu")
		(at 200.939908 -109.561376 180)
		(property "Reference" "R6047"
			(at 0 0 180)
			(layer "F.SilkS")
			(hide yes)
			(effects
				(font
					(size 1.27 1.27)
				)
			)
		)
		(property "Value" ""
			(at 0 0 180)
			(layer "F.Fab")
			(effects
				(font
					(size 1.27 1.27)
				)
			)
		)
		(duplicate_pad_numbers_are_jumpers no)
		(fp_line
			(start 0.7874 0.4064)
			(end -0.7874 0.4064)
			(stroke
				(width 0.1524)
				(type default)
			)
			(layer "F.SilkS")
		)
		(fp_line
			(start 0.7874 -0.4064)
			(end 0.7874 0.4064)
			(stroke
				(width 0.1524)
				(type default)
			)
			(layer "F.SilkS")
		)
		(fp_line
			(start -0.7874 0.4064)
			(end -0.7874 -0.4064)
			(stroke
				(width 0.1524)
				(type default)
			)
			(layer "F.SilkS")
		)
		(fp_line
			(start -0.7874 -0.4064)
			(end 0.7874 -0.4064)
			(stroke
				(width 0.1524)
				(type default)
			)
			(layer "F.SilkS")
		)
		(fp_line
			(start 0.67945 0.3048)
			(end 0.120396 0.3048)
			(stroke
				(width 0.1)
				(type default)
			)
			(layer "F.Fab")
		)
		(fp_line
			(start 0.67945 -0.3048)
			(end 0.67945 0.3048)
			(stroke
				(width 0.1)
				(type default)
			)
			(layer "F.Fab")
		)
		(fp_line
			(start 0.12065 -0.2794)
			(end 0.12065 -0.3048)
			(stroke
				(width 0.1)
				(type default)
			)
			(layer "F.Fab")
		)
		(fp_line
			(start 0.12065 -0.3048)
			(end 0.67945 -0.3048)
			(stroke
				(width 0.1)
				(type default)
			)
			(layer "F.Fab")
		)
		(fp_line
			(start 0.120396 0.3048)
			(end 0.120396 0.2794)
			(stroke
				(width 0.1)
				(type default)
			)
			(layer "F.Fab")
		)
		(fp_line
			(start 0.120396 0.2794)
			(end -0.12065 0.2794)
			(stroke
				(width 0.1)
				(type default)
			)
			(layer "F.Fab")
		)
		(fp_line
			(start -0.12065 0.3048)
			(end -0.67945 0.3048)
			(stroke
				(width 0.1)
				(type default)
			)
			(layer "F.Fab")
		)
		(fp_line
			(start -0.12065 0.2794)
			(end -0.12065 0.3048)
			(stroke
				(width 0.1)
				(type default)
			)
			(layer "F.Fab")
		)
		(fp_line
			(start -0.12065 -0.2794)
			(end 0.12065 -0.2794)
			(stroke
				(width 0.1)
				(type default)
			)
			(layer "F.Fab")
		)
		(fp_line
			(start -0.12065 -0.305054)
			(end -0.12065 -0.2794)
			(stroke
				(width 0.1)
				(type default)
			)
			(layer "F.Fab")
		)
		(fp_line
			(start -0.67945 0.3048)
			(end -0.67945 -0.305054)
			(stroke
				(width 0.1)
				(type default)
			)
			(layer "F.Fab")
		)
		(fp_line
			(start -0.67945 -0.305054)
			(end -0.12065 -0.305054)
			(stroke
				(width 0.1)
				(type default)
			)
			(layer "F.Fab")
		)
		(pad "1" smd circle
			(at -0.40005 0 180)
			(size 0 0)
			(layers "F.Cu" "F.Mask" "F.Paste")
			(net "PWRGD_P3V3_AUX")
		)
		(pad "2" smd circle
			(at 0.40005 0 180)
			(size 0 0)
			(layers "F.Cu" "F.Mask" "F.Paste")
			(net "PWRGD_P3V3_AUX_R")
		)
	)
	(footprint ""
		(layer "F.Cu")
		(at 201.086212 -351.825052)
		(property "Reference" "H49"
			(at -3.0226 -3.96113 0)
			(unlocked yes)
			(layer "F.SilkS")
			(effects
				(font
					(size 0.7874 0.5842)
					(thickness 0.1524)
				)
				(justify left)
			)
		)
		(property "Value" ""
			(at 0 0 0)
			(layer "F.Fab")
			(effects
				(font
					(size 1.27 1.27)
				)
			)
		)
		(duplicate_pad_numbers_are_jumpers no)
		(pad "1" thru_hole circle
			(at 0 0)
			(size 6.1976 6.1976)
			(drill 3.7338)
			(layers "*.Cu" "*.Mask")
			(remove_unused_layers no)
			(net "GND")
			(clearance -0.9779)
			(padstack
				(mode front_inner_back)
				(layer "Inner"
					(shape circle)
					(size 5.5372 5.5372)
					(clearance -0.6477)
				)
				(layer "B.Cu"
					(shape circle)
					(size 6.1976 6.1976)
					(clearance -0.9779)
				)
			)
		)
	)
	(footprint ""
		(layer "F.Cu")
		(at 147.69084 -93.174058 180)
		(property "Reference" "R3307"
			(at 0 0 180)
			(layer "F.SilkS")
			(hide yes)
			(effects
				(font
					(size 1.27 1.27)
				)
			)
		)
		(property "Value" ""
			(at 0 0 180)
			(layer "F.Fab")
			(effects
				(font
					(size 1.27 1.27)
				)
			)
		)
		(duplicate_pad_numbers_are_jumpers no)
		(fp_line
			(start 0.7874 0.4064)
			(end -0.7874 0.4064)
			(stroke
				(width 0.1524)
				(type default)
			)
			(layer "F.SilkS")
		)
		(fp_line
			(start 0.7874 -0.4064)
			(end 0.7874 0.4064)
			(stroke
				(width 0.1524)
				(type default)
			)
			(layer "F.SilkS")
		)
		(fp_line
			(start -0.7874 0.4064)
			(end -0.7874 -0.4064)
			(stroke
				(width 0.1524)
				(type default)
			)
			(layer "F.SilkS")
		)
		(fp_line
			(start -0.7874 -0.4064)
			(end 0.7874 -0.4064)
			(stroke
				(width 0.1524)
				(type default)
			)
			(layer "F.SilkS")
		)
		(fp_line
			(start 0.67945 0.3048)
			(end 0.120396 0.3048)
			(stroke
				(width 0.1)
				(type default)
			)
			(layer "F.Fab")
		)
		(fp_line
			(start 0.67945 -0.3048)
			(end 0.67945 0.3048)
			(stroke
				(width 0.1)
				(type default)
			)
			(layer "F.Fab")
		)
		(fp_line
			(start 0.12065 -0.2794)
			(end 0.12065 -0.3048)
			(stroke
				(width 0.1)
				(type default)
			)
			(layer "F.Fab")
		)
		(fp_line
			(start 0.12065 -0.3048)
			(end 0.67945 -0.3048)
			(stroke
				(width 0.1)
				(type default)
			)
			(layer "F.Fab")
		)
		(fp_line
			(start 0.120396 0.3048)
			(end 0.120396 0.2794)
			(stroke
				(width 0.1)
				(type default)
			)
			(layer "F.Fab")
		)
		(fp_line
			(start 0.120396 0.2794)
			(end -0.12065 0.2794)
			(stroke
				(width 0.1)
				(type default)
			)
			(layer "F.Fab")
		)
		(fp_line
			(start -0.12065 0.3048)
			(end -0.67945 0.3048)
			(stroke
				(width 0.1)
				(type default)
			)
			(layer "F.Fab")
		)
		(fp_line
			(start -0.12065 0.2794)
			(end -0.12065 0.3048)
			(stroke
				(width 0.1)
				(type default)
			)
			(layer "F.Fab")
		)
		(fp_line
			(start -0.12065 -0.2794)
			(end 0.12065 -0.2794)
			(stroke
				(width 0.1)
				(type default)
			)
			(layer "F.Fab")
		)
		(fp_line
			(start -0.12065 -0.305054)
			(end -0.12065 -0.2794)
			(stroke
				(width 0.1)
				(type default)
			)
			(layer "F.Fab")
		)
		(fp_line
			(start -0.67945 0.3048)
			(end -0.67945 -0.305054)
			(stroke
				(width 0.1)
				(type default)
			)
			(layer "F.Fab")
		)
		(fp_line
			(start -0.67945 -0.305054)
			(end -0.12065 -0.305054)
			(stroke
				(width 0.1)
				(type default)
			)
			(layer "F.Fab")
		)
		(pad "1" smd circle
			(at -0.40005 0 180)
			(size 0 0)
			(layers "F.Cu" "F.Mask" "F.Paste")
			(net "OCP_SFF_RBT_ARB_IN_MUX2")
		)
		(pad "2" smd circle
			(at 0.40005 0 180)
			(size 0 0)
			(layers "F.Cu" "F.Mask" "F.Paste")
			(net "OCP_SFF_RBT_ARB_IN_MUX2_R")
		)
	)
)
